FILE_TYPE = CONNECTIVITY;
{Allegro Design Entry HDL 17.2-2016 S081 (4005846) 1/11/2022}
"PAGE_NUMBER" = 318;
0"NC";
1"GND\g";
2"GND\g";
3"GPU_BASE_HMC_READY";
4"P5E_CPU1_PE3_RX_DN<11>";
5"P5E_CPU1_PE3_RX_DP<11>";
6"P5E_CPU1_PE2_RX_DP<11>";
7"P5E_CPU1_PE2_RX_DN<11>";
8"P5E_CPU1_PE3_RX_DP<13>";
9"P5E_CPU1_PE3_RX_DN<13>";
10"P5E_CPU1_PE2_RX_DP<13>";
11"GPU_HMC_PRSNT_N";
12"P5E_CPU1_PE2_RX_DN<13>";
13"P5E_CPU1_PE3_TX_C_DN<13>";
14"FM_SMB_1_ALERT_GPU_N";
15"P5E_CPU1_PE2_TX_C_DN<12>";
16"P5E_CPU1_PE3_TX_C_DP<13>";
17"P5E_CPU1_PE2_TX_C_DN<8>";
18"P5E_CPU1_PE2_TX_C_DP<15>";
19"P5E_CPU1_PE3_RX_DP<9>";
20"P5E_CPU1_PE2_RX_DP<9>";
21"P5E_CPU1_PE2_RX_DN<9>";
22"P5E_CPU1_PE3_TX_C_DN<9>";
23"P5E_CPU1_PE3_TX_C_DP<9>";
24"P5E_CPU1_PE2_TX_C_DN<9>";
25"P5E_CPU1_PE3_RX_DP<12>";
26"P5E_CPU1_PE2_RX_DP<12>";
27"P5E_CPU1_PE2_RX_DN<12>";
28"P5E_CPU1_PE3_TX_C_DP<12>";
29"P5E_CPU1_PE2_TX_C_DN<15>";
30"P5E_CPU1_PE3_TX_C_DN<15>";
31"P5E_CPU1_PE3_TX_C_DP<15>";
32"P5E_CPU1_PE2_RX_DP<15>";
33"P5E_CPU1_PE2_RX_DN<15>";
34"P5E_CPU1_PE3_RX_DP<15>";
35"P5E_CPU1_PE3_RX_DN<15>";
36"GPU_FPGA_EROT_RECOV_BUF_N";
37"GPU_FPGA_BOOT_EN_BUF";
38"P5E_CPU1_PE2_TX_C_DN<14>";
39"P5E_CPU1_PE2_TX_C_DP<14>";
40"P5E_CPU1_PE3_TX_C_DP<14>";
41"P5E_CPU1_PE3_TX_C_DN<14>";
42"P5E_CPU1_PE2_RX_DN<14>";
43"P5E_CPU1_PE2_RX_DP<14>";
44"P5E_CPU1_PE3_RX_DP<14>";
45"P5E_CPU1_PE3_RX_DN<14>";
46"P5E_CPU1_PE2_TX_C_DN<13>";
47"P5E_CPU1_PE2_TX_C_DP<13>";
48"P5E_CPU1_PE2_TX_C_DP<12>";
49"P5E_CPU1_PE3_TX_C_DN<12>";
50"P5E_CPU1_PE3_RX_DN<12>";
51"P5E_CPU1_PE3_TX_C_DP<10>";
52"P5E_CPU1_PE3_RX_DP<10>";
53"P5E_CPU1_PE3_RX_DN<10>";
54"P5E_CPU1_PE3_TX_C_DN<8>";
55"GPU_FPGA_EROT_RST_BUF_N";
56"GPU_BASE_STBY_EN_BUF";
57"P5E_CPU1_PE2_TX_C_DP<8>";
58"P5E_CPU1_PE3_RX_DN<9>";
59"P5E_CPU1_PE2_TX_C_DP<9>";
60"P5E_CPU1_PE3_TX_C_DP<8>";
61"P5E_CPU1_PE2_RX_DN<8>";
62"P5E_CPU1_PE2_RX_DP<8>";
63"P5E_CPU1_PE2_RX_DN<10>";
64"P5E_CPU1_PE3_TX_C_DN<10>";
65"FM_SMB_2_ALERT_GPU_N";
66"P5E_CPU1_PE2_RX_DP<10>";
67"P5E_CPU1_PE2_TX_C_DN<11>";
68"P5E_CPU1_PE3_TX_C_DN<11>";
69"P5E_CPU1_PE2_TX_C_DP<11>";
70"P5E_CPU1_PE3_TX_C_DP<11>";
71"P5E_CPU1_PE2_TX_C_DP<10>";
72"P5E_CPU1_PE2_TX_C_DN<10>";
73"P5E_CPU1_PE3_RX_DN<8>";
74"P5E_CPU1_PE3_RX_DP<8>";
%"UNIVERSAL_GND"
"1","(-2200,-1500)","0","logical_power","I15";
;
CDS_LIB"logical_power"
HDL_POWER"GND";
"A"2;
%"CONN112_10137002101LF"
"1","(-1100,400)","0","pure_quanta","I16";
;
PART_NUMBER"DFHSB2FR012"
MATERIAL"IO"
PART_TYPE"THLF"
LOCATION"J110"
CDS_LIB"pure_quanta"
NEEDS_NO_SIZE"TRUE"
CDS_LMAN_SYM_OUTLINE"-775,1650,775,-1650"
VALUE"CONN112_10137002-101LF"
$SEC"1"
CDS_SEC"1";
"N8"
$PN"N8"55;
"M8"
$PN"M8"2;
"N7"
$PN"N7"2;
"M7"
$PN"M7"24;
"N6"
$PN"N6"65;
"M6"
$PN"M6"2;
"N5"
$PN"N5"2;
"M5"
$PN"M5"67;
"L5"
$PN"L5"69;
"L6"
$PN"L6"72;
"L7"
$PN"L7"59;
"L8"
$PN"L8"17;
"K5"
$PN"K5"2;
"K6"
$PN"K6"71;
"K7"
$PN"K7"2;
"K8"
$PN"K8"57;
"J5"
$PN"J5"70;
"J6"
$PN"J6"2;
"J7"
$PN"J7"23;
"J8"
$PN"J8"2;
"I5"
$PN"I5"68;
"I6"
$PN"I6"51;
"I7"
$PN"I7"22;
"I8"
$PN"I8"60;
"H5"
$PN"H5"2;
"H6"
$PN"H6"64;
"H7"
$PN"H7"2;
"H8"
$PN"H8"54;
"G5"
$PN"G5"7;
"G6"
$PN"G6"2;
"G7"
$PN"G7"21;
"G8"
$PN"G8"2;
"F5"
$PN"F5"6;
"F6"
$PN"F6"63;
"F7"
$PN"F7"20;
"F8"
$PN"F8"61;
"E5"
$PN"E5"2;
"E6"
$PN"E6"66;
"E7"
$PN"E7"2;
"E8"
$PN"E8"62;
"D5"
$PN"D5"5;
"D6"
$PN"D6"2;
"D7"
$PN"D7"19;
"D8"
$PN"D8"2;
"C5"
$PN"C5"4;
"C6"
$PN"C6"52;
"C7"
$PN"C7"58;
"C8"
$PN"C8"74;
"B5"
$PN"B5"2;
"B6"
$PN"B6"53;
"B7"
$PN"B7"2;
"B8"
$PN"B8"73;
"A5"
$PN"A5"3;
"A6"
$PN"A6"2;
"A7"
$PN"A7"56;
"A8"
$PN"A8"2;
%"UNIVERSAL_GND"
"1","(2525,-1500)","0","logical_power","I53";
;
HDL_POWER"GND"
CDS_LIB"logical_power";
"A"1;
%"CONN112_10137002101LF"
"2","(3675,450)","0","pure_quanta","I54";
;
PART_NUMBER"DFHSB2FR012"
PART_TYPE"THLF"
MATERIAL"IO"
LOCATION"J110"
CDS_LMAN_SYM_OUTLINE"-775,1650,775,-1650"
NEEDS_NO_SIZE"TRUE"
CDS_LIB"pure_quanta"
VALUE"CONN112_10137002-101LF"
$SEC"2"
CDS_SEC"2";
"N4"
$PN"N4"14;
"M4"
$PN"M4"1;
"N3"
$PN"N3"1;
"M3"
$PN"M3"46;
"N2"
$PN"N2"37;
"M2"
$PN"M2"1;
"N1"
$PN"N1"1;
"M1"
$PN"M1"29;
"L1"
$PN"L1"18;
"L2"
$PN"L2"38;
"L3"
$PN"L3"47;
"L4"
$PN"L4"15;
"K1"
$PN"K1"1;
"K2"
$PN"K2"39;
"K3"
$PN"K3"1;
"K4"
$PN"K4"48;
"J1"
$PN"J1"31;
"J2"
$PN"J2"1;
"J3"
$PN"J3"16;
"J4"
$PN"J4"1;
"I1"
$PN"I1"30;
"I2"
$PN"I2"40;
"I3"
$PN"I3"13;
"I4"
$PN"I4"28;
"H1"
$PN"H1"1;
"H2"
$PN"H2"41;
"H3"
$PN"H3"1;
"H4"
$PN"H4"49;
"G1"
$PN"G1"33;
"G2"
$PN"G2"1;
"G3"
$PN"G3"12;
"G4"
$PN"G4"1;
"F1"
$PN"F1"32;
"F2"
$PN"F2"42;
"F3"
$PN"F3"10;
"F4"
$PN"F4"27;
"E1"
$PN"E1"1;
"E2"
$PN"E2"43;
"E3"
$PN"E3"1;
"E4"
$PN"E4"26;
"D1"
$PN"D1"35;
"D2"
$PN"D2"1;
"D3"
$PN"D3"9;
"D4"
$PN"D4"1;
"C1"
$PN"C1"34;
"C2"
$PN"C2"45;
"C3"
$PN"C3"8;
"C4"
$PN"C4"50;
"B1"
$PN"B1"1;
"B2"
$PN"B2"44;
"B3"
$PN"B3"1;
"B4"
$PN"B4"25;
"A1"
$PN"A1"36;
"A2"
$PN"A2"1;
"A3"
$PN"A3"11;
"A4"
$PN"A4"1;
END.
